(kicad_pcb
	(version 20260206)
	(generator "pcbnew")
	(generator_version "10.0")
	(general
		(thickness 1.6)
		(legacy_teardrops no)
	)
	(paper "A4")
	(title_block
		(title "v1-chassis-manager — T6M_CM_d_v01_1031_1645.brd")
		(comment 1 "Open CloudServer (Microsoft) / footprints 1151-1153 of 2512")
	)
	(layers
		(0 "F.Cu" signal "TOP")
		(4 "In1.Cu" signal "GND1")
		(6 "In2.Cu" signal "IN1")
		(8 "In3.Cu" signal "VCC1")
		(10 "In4.Cu" signal "VCC2")
		(12 "In5.Cu" signal "GND2")
		(14 "In6.Cu" signal "IN2")
		(16 "In7.Cu" signal "IN3")
		(18 "In8.Cu" signal "GND3")
		(2 "B.Cu" signal "BOTTOM")
		(9 "F.Adhes" user "F.Adhesive")
		(11 "B.Adhes" user "B.Adhesive")
		(13 "F.Paste" user "Package Geometry/Pastemask Top")
		(15 "B.Paste" user "Package Geometry/Pastemask Bottom")
		(5 "F.SilkS" user "Ref Des/Silkscreen Top")
		(7 "B.SilkS" user "Ref Des/Silkscreen Bottom")
		(1 "F.Mask" user "Board Geometry/Soldermask Top")
		(3 "B.Mask" user "Board Geometry/Soldermask Bottom")
		(17 "Dwgs.User" user "User.Drawings")
		(19 "Cmts.User" user "User.Comments")
		(21 "Eco1.User" user "User.Eco1")
		(23 "Eco2.User" user "User.Eco2")
		(25 "Edge.Cuts" user "Board Geometry/Outline")
		(27 "Margin" user)
		(31 "F.CrtYd" user "Package Geometry/Place Bound Top")
		(29 "B.CrtYd" user "Package Geometry/Place Bound Bottom")
		(35 "F.Fab" user "Ref Des/Assembly Top")
		(33 "B.Fab" user "Ref Des/Assembly Bottom")
	)
	(footprint ""
		(layer "F.Cu")
		(at 98.297746 -15.941294 90)
		(property "Reference" "R190"
			(at 0.688848 -0.963168 90)
			(unlocked yes)
			(layer "F.SilkS")
			(effects
				(font
					(size 0.7874 0.5842)
					(thickness 0.1524)
				)
				(justify left)
			)
		)
		(property "Value" ""
			(at 0 0 90)
			(layer "F.Fab")
			(effects
				(font
					(size 1.27 1.27)
				)
			)
		)
		(duplicate_pad_numbers_are_jumpers no)
		(fp_line
			(start 0.7874 -0.4064)
			(end 0.7874 0.4064)
			(stroke
				(width 0.1524)
				(type default)
			)
			(layer "F.SilkS")
		)
		(fp_line
			(start -0.7874 -0.4064)
			(end 0.7874 -0.4064)
			(stroke
				(width 0.1524)
				(type default)
			)
			(layer "F.SilkS")
		)
		(fp_line
			(start 0.7874 0.4064)
			(end -0.7874 0.4064)
			(stroke
				(width 0.1524)
				(type default)
			)
			(layer "F.SilkS")
		)
		(fp_line
			(start -0.7874 0.4064)
			(end -0.7874 -0.4064)
			(stroke
				(width 0.1524)
				(type default)
			)
			(layer "F.SilkS")
		)
		(fp_poly
			(pts
				(xy -0.508 0.2794) (xy -0.508 0.2286) (xy -0.635 0.2286) (xy -0.635 -0.254) (xy -0.5334 -0.254)
				(xy -0.5334 -0.2794) (xy 0.5334 -0.2794) (xy 0.5334 -0.254) (xy 0.635 -0.254) (xy 0.635 0.254) (xy 0.5334 0.254)
				(xy 0.5334 0.2794)
			)
			(stroke
				(width 0)
				(type default)
			)
			(fill no)
			(layer "F.CrtYd")
		)
		(pad "1" smd rect
			(at 0.40005 0 90)
			(size 0.4572 0.508)
			(layers "F.Cu" "F.Mask" "F.Paste")
			(net "LPC_CPU_NODE1_LAD0")
		)
		(pad "2" smd rect
			(at -0.40005 0 90)
			(size 0.4572 0.508)
			(layers "F.Cu" "F.Mask" "F.Paste")
			(net "LPC_CPU_TPM_LAD0")
		)
	)
	(footprint ""
		(layer "F.Cu")
		(at 11.04392 -8.35279)
		(property "Reference" "U11"
			(at -4.445762 0.18923 90)
			(unlocked yes)
			(layer "F.SilkS")
			(effects
				(font
					(size 0.7874 0.5842)
					(thickness 0.1524)
				)
			)
		)
		(property "Value" ""
			(at 0 0 0)
			(layer "F.Fab")
			(effects
				(font
					(size 1.27 1.27)
				)
			)
		)
		(duplicate_pad_numbers_are_jumpers no)
		(fp_line
			(start -1.651 -2.0574)
			(end 1.651 -2.0574)
			(stroke
				(width 0.1524)
				(type default)
			)
			(layer "F.SilkS")
		)
		(fp_line
			(start -1.651 -0.381)
			(end -1.651 -2.0574)
			(stroke
				(width 0.1524)
				(type default)
			)
			(layer "F.SilkS")
		)
		(fp_line
			(start -1.651 0.381)
			(end -1.016 0)
			(stroke
				(width 0.1524)
				(type default)
			)
			(layer "F.SilkS")
		)
		(fp_line
			(start -1.651 2.0574)
			(end -1.651 0.381)
			(stroke
				(width 0.1524)
				(type default)
			)
			(layer "F.SilkS")
		)
		(fp_line
			(start -1.016 0)
			(end -1.651 -0.381)
			(stroke
				(width 0.1524)
				(type default)
			)
			(layer "F.SilkS")
		)
		(fp_line
			(start 1.651 -2.0574)
			(end 1.651 2.0574)
			(stroke
				(width 0.1524)
				(type default)
			)
			(layer "F.SilkS")
		)
		(fp_line
			(start 1.651 2.0574)
			(end -1.651 2.0574)
			(stroke
				(width 0.1524)
				(type default)
			)
			(layer "F.SilkS")
		)
		(fp_rect
			(start -1.524 1.905)
			(end 1.524 -1.905)
			(stroke
				(width 0)
				(type default)
			)
			(fill no)
			(layer "F.CrtYd")
		)
		(pad "1" smd rect
			(at -0.94996 1.225042)
			(size 0.5588 1.3462)
			(layers "F.Cu" "F.Mask" "F.Paste")
			(net "PV_VDDR_NODE1_VREF_RW")
		)
		(pad "2" smd rect
			(at 0 1.225042)
			(size 0.5588 1.3462)
			(layers "F.Cu" "F.Mask" "F.Paste")
			(net "GND")
		)
		(pad "3" smd rect
			(at 0.94996 1.225042)
			(size 0.5588 1.3462)
			(layers "F.Cu" "F.Mask" "F.Paste")
			(net "PV_VDDR_NODE1_VREF_R")
		)
		(pad "4" smd rect
			(at 0.94996 -1.225042)
			(size 0.5588 1.3462)
			(layers "F.Cu" "F.Mask" "F.Paste")
			(net "PV_VDDR_NODE1_VREF_R")
		)
		(pad "5" smd rect
			(at -0.94996 -1.225042)
			(size 0.5588 1.3462)
			(layers "F.Cu" "F.Mask" "F.Paste")
			(net "P5V_STB_NODE1")
		)
	)
	(footprint ""
		(layer "F.Cu")
		(at 191.389 -121.666)
		(property "Reference" "R1265"
			(at 0.2032 2.43967 0)
			(unlocked yes)
			(layer "F.SilkS")
			(effects
				(font
					(size 0.7874 0.5842)
					(thickness 0.1524)
				)
				(justify left)
			)
		)
		(property "Value" ""
			(at 0 0 0)
			(layer "F.Fab")
			(effects
				(font
					(size 1.27 1.27)
				)
			)
		)
		(duplicate_pad_numbers_are_jumpers no)
		(fp_line
			(start -0.7874 -0.4064)
			(end 0.7874 -0.4064)
			(stroke
				(width 0.1524)
				(type default)
			)
			(layer "F.SilkS")
		)
		(fp_line
			(start -0.7874 0.4064)
			(end -0.7874 -0.4064)
			(stroke
				(width 0.1524)
				(type default)
			)
			(layer "F.SilkS")
		)
		(fp_line
			(start 0.7874 -0.4064)
			(end 0.7874 0.4064)
			(stroke
				(width 0.1524)
				(type default)
			)
			(layer "F.SilkS")
		)
		(fp_line
			(start 0.7874 0.4064)
			(end -0.7874 0.4064)
			(stroke
				(width 0.1524)
				(type default)
			)
			(layer "F.SilkS")
		)
		(fp_poly
			(pts
				(xy -0.508 0.2794) (xy -0.508 0.2286) (xy -0.635 0.2286) (xy -0.635 -0.254) (xy -0.5334 -0.254)
				(xy -0.5334 -0.2794) (xy 0.5334 -0.2794) (xy 0.5334 -0.254) (xy 0.635 -0.254) (xy 0.635 0.254) (xy 0.5334 0.254)
				(xy 0.5334 0.2794)
			)
			(stroke
				(width 0)
				(type default)
			)
			(fill no)
			(layer "F.CrtYd")
		)
		(pad "1" smd rect
			(at 0.40005 0)
			(size 0.4572 0.508)
			(layers "F.Cu" "F.Mask" "F.Paste")
			(net "SIO_JTAG_CPLD1_TDI_R")
		)
		(pad "2" smd rect
			(at -0.40005 0)
			(size 0.4572 0.508)
			(layers "F.Cu" "F.Mask" "F.Paste")
			(net "SIO_JTAG_CPLD1_TDI")
		)
	)
)
